# TIMECARD (Time Appliance Project (Time Card)) — schematic netlist excerpt (pin names and nets, part order shuffled) for the footprints in the layout excerpt that follows; sources: Cadence DE-HDL packaged netlist, KiCad conversion of R4006-B0001-02_R01.brd

R252  RESISTOR  0OHM -  pkg SMC_0603R_H024  page 29 : \1\ = XP1R0V_AGND ; \2\ = XP1R0V_FB_R_TO_AGND
R469  RESISTOR  33OHM 1%  pkg SMC_0402R_H016  page 24 : \1\ = R_FT4232_TDO ; \2\ = FT4232_TDO_MISO

(kicad_pcb
	(version 20260206)
	(generator "pcbnew")
	(generator_version "10.0")
	(general
		(thickness 1.6)
		(legacy_teardrops no)
	)
	(paper "A4")
	(title_block
		(title "timecard-production-celestica-r4006 — R4006-B0001-02_R01.brd")
		(comment 1 "Time Appliance Project (Time Card) / footprints 956-957 of 1113")
	)
	(layers
		(0 "F.Cu" signal "TOP")
		(4 "In1.Cu" signal "L02_GND1")
		(6 "In2.Cu" signal "L03_SIG1")
		(8 "In3.Cu" signal "L04_GND2")
		(10 "In4.Cu" signal "L05_VCC1")
		(12 "In5.Cu" signal "L06_VCC2")
		(14 "In6.Cu" signal "L07_GND3")
		(16 "In7.Cu" signal "L08_SIG2")
		(18 "In8.Cu" signal "L09_GND4")
		(2 "B.Cu" signal "BOTTOM")
		(9 "F.Adhes" user "F.Adhesive")
		(11 "B.Adhes" user "B.Adhesive")
		(13 "F.Paste" user "Package Geometry/Pastemask Top")
		(15 "B.Paste" user "Package Geometry/Pastemask Bottom")
		(5 "F.SilkS" user "Ref Des/Silkscreen Top")
		(7 "B.SilkS" user "Ref Des/Silkscreen Bottom")
		(1 "F.Mask" user "Board Geometry/Soldermask Top")
		(3 "B.Mask" user "Board Geometry/Soldermask Bottom")
		(17 "Dwgs.User" user "User.Drawings")
		(19 "Cmts.User" user "User.Comments")
		(21 "Eco1.User" user "User.Eco1")
		(23 "Eco2.User" user "User.Eco2")
		(25 "Edge.Cuts" user "Board Geometry/Outline")
		(27 "Margin" user)
		(31 "F.CrtYd" user "Package Geometry/Place Bound Top")
		(29 "B.CrtYd" user "Package Geometry/Place Bound Bottom")
		(35 "F.Fab" user "Ref Des/Assembly Top")
		(33 "B.Fab" user "Ref Des/Assembly Bottom")
	)
	(footprint ""
		(layer "B.Cu")
		(at 144.78 -59.563 90)
		(property "Reference" "R252"
			(at 0.889 3.13563 270)
			(unlocked yes)
			(layer "B.SilkS")
			(effects
				(font
					(size 0.7874 0.5842)
					(thickness 0.1524)
				)
				(justify mirror)
			)
		)
		(property "Value" "VAL*"
			(at 0.0254 2.524506 90)
			(unlocked yes)
			(layer "B.Fab")
			(hide yes)
			(effects
				(font
					(size 0.7874 0.5842)
					(thickness 0.1524)
				)
				(justify mirror)
			)
		)
		(property "Device Type" "RESISTOR-G156-100R0-J0,0OHM,-"
			(at 0 1.610106 90)
			(unlocked yes)
			(layer "B.Fab")
			(hide yes)
			(effects
				(font
					(size 0.7874 0.5842)
					(thickness 0.1524)
				)
				(justify mirror)
			)
		)
		(property "User Part Number" "PARTNUM*"
			(at 0.0254 4.505706 90)
			(unlocked yes)
			(layer "Cmts.User")
			(hide yes)
			(effects
				(font
					(size 0.7874 0.5842)
					(thickness 0.1524)
				)
				(justify mirror)
			)
		)
		(property "Tolerance" "TOL*"
			(at 0.0254 3.464306 90)
			(unlocked yes)
			(layer "Cmts.User")
			(hide yes)
			(effects
				(font
					(size 0.7874 0.5842)
					(thickness 0.1524)
				)
				(justify mirror)
			)
		)
		(duplicate_pad_numbers_are_jumpers no)
		(fp_line
			(start 1.3208 -0.7112)
			(end -1.3208 -0.7112)
			(stroke
				(width 0.1)
				(type default)
			)
			(layer "B.SilkS")
		)
		(fp_line
			(start -1.3208 -0.7112)
			(end -1.3208 0.7112)
			(stroke
				(width 0.1)
				(type default)
			)
			(layer "B.SilkS")
		)
		(fp_line
			(start 1.3208 0.7112)
			(end 1.3208 -0.7112)
			(stroke
				(width 0.1)
				(type default)
			)
			(layer "B.SilkS")
		)
		(fp_line
			(start -1.3208 0.7112)
			(end 1.3208 0.7112)
			(stroke
				(width 0.1)
				(type default)
			)
			(layer "B.SilkS")
		)
		(fp_rect
			(start -1.3208 -0.7112)
			(end 1.3208 0.7112)
			(stroke
				(width 0)
				(type default)
			)
			(fill no)
			(layer "B.CrtYd")
		)
		(fp_line
			(start 0.8128 -0.4572)
			(end -0.8128 -0.4572)
			(stroke
				(width 0.1)
				(type default)
			)
			(layer "B.Fab")
		)
		(fp_line
			(start -0.8128 -0.4572)
			(end -0.8128 0.4572)
			(stroke
				(width 0.1)
				(type default)
			)
			(layer "B.Fab")
		)
		(fp_line
			(start 0.8128 0.4572)
			(end 0.8128 -0.4572)
			(stroke
				(width 0.1)
				(type default)
			)
			(layer "B.Fab")
		)
		(fp_line
			(start -0.8128 0.4572)
			(end 0.8128 0.4572)
			(stroke
				(width 0.1)
				(type default)
			)
			(layer "B.Fab")
		)
		(pad "1" smd rect
			(at 0.6858 0 270)
			(size 0.762 0.8636)
			(layers "B.Cu" "B.Mask" "B.Paste")
			(net "XP1R0V_AGND")
		)
		(pad "2" smd rect
			(at -0.6858 0 270)
			(size 0.762 0.8636)
			(layers "B.Cu" "B.Mask" "B.Paste")
			(net "XP1R0V_FB_R_TO_AGND")
		)
		(zone
			(layer "B.Cu")
			(hatch none 0.5)
			(connect_pads
				(clearance 0)
			)
			(min_thickness 0.25)
			(keepout
				(tracks allowed)
				(vias not_allowed)
				(pads allowed)
				(copperpour not_allowed)
				(footprints allowed)
			)
			(placement
				(enabled no)
				(sheetname "")
			)
			(fill
				(thermal_gap 0.5)
				(thermal_bridge_width 0.5)
				(island_removal_mode 0)
			)
			(polygon
				(pts
					(xy 144.3228 -59.4106) (xy 145.2372 -59.4106) (xy 145.2372 -59.7154) (xy 144.3228 -59.7154)
				)
			)
		)
	)
	(footprint ""
		(layer "B.Cu")
		(at 22.606 -88.9 180)
		(property "Reference" "R469"
			(at -1.016 -3.59537 0)
			(unlocked yes)
			(layer "B.SilkS")
			(effects
				(font
					(size 0.7874 0.5842)
					(thickness 0.1524)
				)
				(justify mirror)
			)
		)
		(property "Value" "VAL*"
			(at -0.02032 2.13233 180)
			(unlocked yes)
			(layer "B.Fab")
			(hide yes)
			(effects
				(font
					(size 0.7874 0.5842)
					(thickness 0.1524)
				)
				(justify mirror)
			)
		)
		(property "Tolerance" "TOL*"
			(at -0.044704 3.05435 180)
			(unlocked yes)
			(layer "Cmts.User")
			(hide yes)
			(effects
				(font
					(size 0.7874 0.5842)
					(thickness 0.1524)
				)
				(justify mirror)
			)
		)
		(property "User Part Number" "PARTNUM*"
			(at -0.02032 4.024884 180)
			(unlocked yes)
			(layer "Cmts.User")
			(hide yes)
			(effects
				(font
					(size 0.7874 0.5842)
					(thickness 0.1524)
				)
				(justify mirror)
			)
		)
		(property "Device Type" "RESISTOR-G155-133R0-01,33OHM,1%"
			(at -0.008382 1.210564 180)
			(unlocked yes)
			(layer "B.Fab")
			(hide yes)
			(effects
				(font
					(size 0.7874 0.5842)
					(thickness 0.1524)
				)
				(justify mirror)
			)
		)
		(duplicate_pad_numbers_are_jumpers no)
		(fp_line
			(start 1.143 0.5588)
			(end -1.143 0.5588)
			(stroke
				(width 0.1)
				(type default)
			)
			(layer "B.SilkS")
		)
		(fp_line
			(start 1.143 -0.5588)
			(end 1.143 0.5588)
			(stroke
				(width 0.1)
				(type default)
			)
			(layer "B.SilkS")
		)
		(fp_line
			(start -1.143 0.5588)
			(end -1.143 -0.5588)
			(stroke
				(width 0.1)
				(type default)
			)
			(layer "B.SilkS")
		)
		(fp_line
			(start -1.143 -0.5588)
			(end 1.143 -0.5588)
			(stroke
				(width 0.1)
				(type default)
			)
			(layer "B.SilkS")
		)
		(fp_poly
			(pts
				(xy 1.143 0.5588) (xy -1.143 0.5588) (xy -1.143 -0.5588) (xy 1.143 -0.5588)
			)
			(stroke
				(width 0)
				(type default)
			)
			(fill no)
			(layer "B.CrtYd")
		)
		(fp_line
			(start 0.508 0.3048)
			(end -0.508 0.3048)
			(stroke
				(width 0.1)
				(type default)
			)
			(layer "B.Fab")
		)
		(fp_line
			(start 0.508 -0.3048)
			(end 0.508 0.3048)
			(stroke
				(width 0.1)
				(type default)
			)
			(layer "B.Fab")
		)
		(fp_line
			(start -0.508 0.3048)
			(end -0.508 -0.3048)
			(stroke
				(width 0.1)
				(type default)
			)
			(layer "B.Fab")
		)
		(fp_line
			(start -0.508 -0.3048)
			(end 0.508 -0.3048)
			(stroke
				(width 0.1)
				(type default)
			)
			(layer "B.Fab")
		)
		(pad "1" smd rect
			(at 0.5334 0)
			(size 0.7112 0.6096)
			(layers "B.Cu" "B.Mask" "B.Paste")
			(net "R_FT4232_TDO")
		)
		(pad "2" smd rect
			(at -0.5334 0)
			(size 0.7112 0.6096)
			(layers "B.Cu" "B.Mask" "B.Paste")
			(net "FT4232_TDO_MISO")
		)
		(zone
			(layer "B.Cu")
			(hatch none 0.5)
			(connect_pads
				(clearance 0)
			)
			(min_thickness 0.25)
			(keepout
				(tracks allowed)
				(vias not_allowed)
				(pads allowed)
				(copperpour not_allowed)
				(footprints allowed)
			)
			(placement
				(enabled no)
				(sheetname "")
			)
			(fill
				(thermal_gap 0.5)
				(thermal_bridge_width 0.5)
				(island_removal_mode 0)
			)
			(polygon
				(pts
					(xy 22.5298 -89.2048) (xy 22.5298 -88.5952) (xy 22.6822 -88.5952) (xy 22.6822 -89.2048)
				)
			)
		)
		(zone
			(layer "B.Cu")
			(hatch none 0.5)
			(connect_pads
				(clearance 0)
			)
			(min_thickness 0.25)
			(keepout
				(tracks not_allowed)
				(vias allowed)
				(pads allowed)
				(copperpour not_allowed)
				(footprints allowed)
			)
			(placement
				(enabled no)
				(sheetname "")
			)
			(fill
				(thermal_gap 0.5)
				(thermal_bridge_width 0.5)
				(island_removal_mode 0)
			)
			(polygon
				(pts
					(xy 22.5298 -89.2048) (xy 22.5298 -88.5952) (xy 22.6822 -88.5952) (xy 22.6822 -89.2048)
				)
			)
		)
	)
)
